(kicad_pcb
	(version 20221018)
	(generator pcbnew)
	(general
    (thickness 1.562)
  )
	(paper "A4")
	(title_block
    (title "Thunderbolt PCIe Adaper")
    (date "2024-07-09")
    (rev "1.0.3")
    (comment 1 "www.antmicro.com")
    (comment 2 "Antmicro Ltd.")
		(comment 9 "footprints 142-150 of 271")
	)
	(layers
    (0 "F.Cu" signal)
    (1 "In1.Cu" signal)
    (2 "In2.Cu" signal)
    (3 "In3.Cu" signal)
    (4 "In4.Cu" signal)
    (31 "B.Cu" signal)
    (32 "B.Adhes" user "B.Adhesive")
    (33 "F.Adhes" user "F.Adhesive")
    (34 "B.Paste" user)
    (35 "F.Paste" user)
    (36 "B.SilkS" user "B.Silkscreen")
    (37 "F.SilkS" user "F.Silkscreen")
    (38 "B.Mask" user)
    (39 "F.Mask" user)
    (40 "Dwgs.User" user "User.Drawings")
    (41 "Cmts.User" user "User.Comments")
    (42 "Eco1.User" user "User.Eco1")
    (43 "Eco2.User" user "User.Eco2")
    (44 "Edge.Cuts" user)
    (45 "Margin" user)
    (46 "B.CrtYd" user "B.Courtyard")
    (47 "F.CrtYd" user "F.Courtyard")
    (48 "B.Fab" user)
    (49 "F.Fab" user)
  )
	(footprint "antmicro-footprints:R_0402_1005Metric" (layer "B.Cu")
    (at 160.91 59.47 -90)
    (descr "Resistor SMD 0402")
    (tags "resistor SMD 0402")
    (property "Author" "Antmicro")
    (property "License" "Apache-2.0")
    (property "MPN" "CR0402-FX-1003GLF")
    (property "Manufacturer" "Bourns")
    (property "Sheetfile" "power.kicad_sch")
    (property "Sheetname" "Power")
    (property "Tolerance" "1%")
    (property "Val" "100k")
    (property "ki_description" "SMD Chip Resistor, 100 kohm, ± 1%, 62.5 mW, 0402 [1005 Metric], Thick Film, General Purpose")
    (property "ki_keywords" "0402, SMT, RESISTOR, PASSIVE")
    (attr smd)
    (fp_text reference "R4" (at -3.082 -0.507 90) (layer "B.SilkS")
        (effects (font (size 0.7 0.7) (thickness 0.15)) (justify left bottom mirror))
    )
    (fp_text value "R_100k_0402" (at -1.011843 -1.772047 90) (layer "B.Fab")
        (effects (font (size 0.7 0.7) (thickness 0.15)) (justify left bottom mirror))
    )
    (fp_text user "Author: Antmicro" (at -0.95 -4.169 90) (layer "B.Fab") hide
        (effects (font (size 0.7 0.7) (thickness 0.15)) (justify left bottom mirror))
    )
    (fp_text user "${REFERENCE}" (at -0.95 -3.168 90) (layer "B.Fab") hide
        (effects (font (size 0.7 0.7) (thickness 0.15)) (justify left bottom mirror))
    )
    (fp_text user "License: Apache-2.0" (at -0.95 -5.169 90) (layer "B.Fab") hide
        (effects (font (size 0.7 0.7) (thickness 0.15)) (justify left bottom mirror))
    )
    (fp_rect (start -0.925 0.47) (end 0.925 -0.47)
      (stroke (width 0.05) (type default)) (fill none) (layer "B.CrtYd"))
    (fp_rect (start -0.5 0.25) (end 0.5 -0.25)
      (stroke (width 0.15) (type solid)) (fill none) (layer "B.Fab"))
    (pad "1" smd roundrect (at -0.48 0 270) (size 0.59 0.64) (layers "B.Cu" "B.Paste" "B.Mask") (roundrect_rratio 0.25)
      (net 1 "GND") (pintype "passive"))
    (pad "2" smd roundrect (at 0.48 0 270) (size 0.59 0.64) (layers "B.Cu" "B.Paste" "B.Mask") (roundrect_rratio 0.25)
      (net 58 "HPD") (pintype "passive"))
  )
	(footprint "antmicro-footprints:R_0402_1005Metric" (layer "B.Cu")
    (at 116.19 91.63 90)
    (descr "Resistor SMD 0402")
    (tags "resistor SMD 0402")
    (property "Author" "Antmicro")
    (property "License" "Apache-2.0")
    (property "MPN" "CR0402-FX-2201GLF")
    (property "Manufacturer" "Bourns")
    (property "Sheetfile" "power.kicad_sch")
    (property "Sheetname" "Power")
    (property "Tolerance" "1%")
    (property "Val" "2k2")
    (property "ki_description" "SMD Chip Resistor, 2.2 kohm, ± 1%, 62.5 mW, 0402 [1005 Metric], Thick Film, General Purpose")
    (property "ki_keywords" "0402, SMT, RESISTOR, PASSIVE")
    (attr smd)
    (fp_text reference "R46" (at 1.079 3.515 270) (layer "B.SilkS")
        (effects (font (size 0.7 0.7) (thickness 0.15)) (justify left bottom mirror))
    )
    (fp_text value "R_2k2_0402" (at -1.011843 -1.772047 270) (layer "B.Fab")
        (effects (font (size 0.7 0.7) (thickness 0.15)) (justify left bottom mirror))
    )
    (fp_text user "Author: Antmicro" (at -0.95 -4.169 270) (layer "B.Fab") hide
        (effects (font (size 0.7 0.7) (thickness 0.15)) (justify left bottom mirror))
    )
    (fp_text user "${REFERENCE}" (at -0.95 -3.168 270) (layer "B.Fab") hide
        (effects (font (size 0.7 0.7) (thickness 0.15)) (justify left bottom mirror))
    )
    (fp_text user "License: Apache-2.0" (at -0.95 -5.169 270) (layer "B.Fab") hide
        (effects (font (size 0.7 0.7) (thickness 0.15)) (justify left bottom mirror))
    )
    (fp_rect (start -0.925 0.47) (end 0.925 -0.47)
      (stroke (width 0.05) (type default)) (fill none) (layer "B.CrtYd"))
    (fp_rect (start -0.5 0.25) (end 0.5 -0.25)
      (stroke (width 0.15) (type solid)) (fill none) (layer "B.Fab"))
    (pad "1" smd roundrect (at -0.48 0 90) (size 0.59 0.64) (layers "B.Cu" "B.Paste" "B.Mask") (roundrect_rratio 0.25)
      (net 1 "GND") (pintype "passive"))
    (pad "2" smd roundrect (at 0.48 0 90) (size 0.59 0.64) (layers "B.Cu" "B.Paste" "B.Mask") (roundrect_rratio 0.25)
      (net 121 "Net-(D3-C)") (pintype "passive"))
  )
	(footprint "antmicro-footprints:R_0402_1005Metric" (layer "B.Cu")
    (at 141.325 66.82 90)
    (descr "Resistor SMD 0402")
    (tags "resistor SMD 0402")
    (property "Author" "Antmicro")
    (property "License" "Apache-2.0")
    (property "MPN" "CR0402-FX-1002GLF")
    (property "Manufacturer" "Bourns")
    (property "Sheetfile" "tb.kicad_sch")
    (property "Sheetname" "TB Controller")
    (property "Tolerance" "1%")
    (property "Val" "10k")
    (property "ki_description" "SMD Chip Resistor, 10 kohm, ± 1%, 62.5 mW, 0402 [1005 Metric], Thick Film, General Purpose")
    (property "ki_keywords" "0402, SMT, RESISTOR, PASSIVE")
    (attr smd)
    (fp_text reference "R85" (at 3.066 0.398 270) (layer "B.SilkS")
        (effects (font (size 0.7 0.7) (thickness 0.15)) (justify left bottom mirror))
    )
    (fp_text value "R_10k_0402" (at -1.011843 -1.772047 270) (layer "B.Fab")
        (effects (font (size 0.7 0.7) (thickness 0.15)) (justify left bottom mirror))
    )
    (fp_text user "License: Apache-2.0" (at -0.95 -5.169 270) (layer "B.Fab") hide
        (effects (font (size 0.7 0.7) (thickness 0.15)) (justify left bottom mirror))
    )
    (fp_text user "Author: Antmicro" (at -0.95 -4.169 270) (layer "B.Fab") hide
        (effects (font (size 0.7 0.7) (thickness 0.15)) (justify left bottom mirror))
    )
    (fp_text user "${REFERENCE}" (at -0.95 -3.168 270) (layer "B.Fab") hide
        (effects (font (size 0.7 0.7) (thickness 0.15)) (justify left bottom mirror))
    )
    (fp_rect (start -0.925 0.47) (end 0.925 -0.47)
      (stroke (width 0.05) (type default)) (fill none) (layer "B.CrtYd"))
    (fp_rect (start -0.5 0.25) (end 0.5 -0.25)
      (stroke (width 0.15) (type solid)) (fill none) (layer "B.Fab"))
    (pad "1" smd roundrect (at -0.48 0 90) (size 0.59 0.64) (layers "B.Cu" "B.Paste" "B.Mask") (roundrect_rratio 0.25)
      (net 200 "Net-(U4C-POC_GPIO_3)") (pintype "passive"))
    (pad "2" smd roundrect (at 0.48 0 90) (size 0.59 0.64) (layers "B.Cu" "B.Paste" "B.Mask") (roundrect_rratio 0.25)
      (net 1 "GND") (pintype "passive"))
  )
	(footprint "antmicro-footprints:R_0402_1005Metric" (layer "B.Cu")
    (at 106.83 91.765 -90)
    (descr "Resistor SMD 0402")
    (tags "resistor SMD 0402")
    (property "Author" "Antmicro")
    (property "License" "Apache-2.0")
    (property "MPN" "CR0402-FX-1002GLF")
    (property "Manufacturer" "Bourns")
    (property "Sheetfile" "power.kicad_sch")
    (property "Sheetname" "Power")
    (property "Tolerance" "1%")
    (property "Val" "10k")
    (property "ki_description" "SMD Chip Resistor, 10 kohm, ± 1%, 62.5 mW, 0402 [1005 Metric], Thick Film, General Purpose")
    (property "ki_keywords" "0402, SMT, RESISTOR, PASSIVE")
    (attr smd)
    (fp_text reference "R93" (at -1.087 0.658 90) (layer "B.SilkS")
        (effects (font (size 0.7 0.7) (thickness 0.15)) (justify left bottom mirror))
    )
    (fp_text value "R_10k_0402" (at -1.011843 -1.772047 90) (layer "B.Fab")
        (effects (font (size 0.7 0.7) (thickness 0.15)) (justify left bottom mirror))
    )
    (fp_text user "License: Apache-2.0" (at -0.95 -5.169 90) (layer "B.Fab") hide
        (effects (font (size 0.7 0.7) (thickness 0.15)) (justify left bottom mirror))
    )
    (fp_text user "${REFERENCE}" (at -0.95 -3.168 90) (layer "B.Fab") hide
        (effects (font (size 0.7 0.7) (thickness 0.15)) (justify left bottom mirror))
    )
    (fp_text user "Author: Antmicro" (at -0.95 -4.169 90) (layer "B.Fab") hide
        (effects (font (size 0.7 0.7) (thickness 0.15)) (justify left bottom mirror))
    )
    (fp_rect (start -0.925 0.47) (end 0.925 -0.47)
      (stroke (width 0.05) (type default)) (fill none) (layer "B.CrtYd"))
    (fp_rect (start -0.5 0.25) (end 0.5 -0.25)
      (stroke (width 0.15) (type solid)) (fill none) (layer "B.Fab"))
    (pad "1" smd roundrect (at -0.48 0 270) (size 0.59 0.64) (layers "B.Cu" "B.Paste" "B.Mask") (roundrect_rratio 0.25)
      (net 1 "GND") (pintype "passive"))
    (pad "2" smd roundrect (at 0.48 0 270) (size 0.59 0.64) (layers "B.Cu" "B.Paste" "B.Mask") (roundrect_rratio 0.25)
      (net 141 "Net-(Q3-REF)") (pintype "passive"))
  )
	(footprint "antmicro-footprints:C_0402_1005Metric" (layer "B.Cu")
    (at 113.675 84.69 180)
    (descr "Capacitor SMD 0402")
    (tags "capacitor SMD 0402")
    (property "Author" "Antmicro")
    (property "Dielectric" "")
    (property "License" "Apache-2.0")
    (property "MPN" "GCM155R71H223MA55D")
    (property "Manufacturer" "Murata")
    (property "Sheetfile" "power.kicad_sch")
    (property "Sheetname" "Power")
    (property "Val" "22n")
    (property "Voltage" "")
    (property "ki_description" "SMD Multilayer Ceramic Capacitors, 0.022 µF, 50 V, 20%, 0402 [1005 Metric], X7R")
    (property "ki_keywords" "0402, SMT, CAPACITOR, PASSIVE, CERAMIC, MLCC")
    (attr smd)
    (fp_text reference "C19" (at -3.038 -0.4) (layer "B.SilkS")
        (effects (font (size 0.7 0.7) (thickness 0.15)) (justify left bottom mirror))
    )
    (fp_text value "C_22n_0402" (at -1.022927 -2.155213) (layer "B.Fab")
        (effects (font (size 0.7 0.7) (thickness 0.15)) (justify left bottom mirror))
    )
    (fp_text user "${REFERENCE}" (at -0.939 -4.599) (layer "B.Fab") hide
        (effects (font (size 0.7 0.7) (thickness 0.15)) (justify left bottom mirror))
    )
    (fp_text user "Author: Antmicro" (at -0.939 -3.399) (layer "B.Fab") hide
        (effects (font (size 0.7 0.7) (thickness 0.15)) (justify left bottom mirror))
    )
    (fp_text user "License: Apache-2.0" (at -0.939 -5.799) (layer "B.Fab") hide
        (effects (font (size 0.7 0.7) (thickness 0.15)) (justify left bottom mirror))
    )
    (fp_rect (start -0.925 0.47) (end 0.925 -0.47)
      (stroke (width 0.05) (type default)) (fill none) (layer "B.CrtYd"))
    (fp_line (start -0.494 -0.248) (end -0.494 0.25)
      (stroke (width 0.15) (type solid)) (layer "B.Fab"))
    (fp_line (start -0.494 0.25) (end 0.504 0.25)
      (stroke (width 0.15) (type solid)) (layer "B.Fab"))
    (fp_line (start 0.504 -0.248) (end -0.494 -0.248)
      (stroke (width 0.15) (type solid)) (layer "B.Fab"))
    (fp_line (start 0.504 0.25) (end 0.504 -0.248)
      (stroke (width 0.15) (type solid)) (layer "B.Fab"))
    (pad "1" smd roundrect (at -0.48 0 180) (size 0.59 0.64) (layers "B.Cu" "B.Paste" "B.Mask") (roundrect_rratio 0.25)
      (net 1 "GND") (pintype "passive"))
    (pad "2" smd roundrect (at 0.48 0 180) (size 0.59 0.64) (layers "B.Cu" "B.Paste" "B.Mask") (roundrect_rratio 0.25)
      (net 92 "Net-(U1-SS)") (pintype "passive"))
  )
	(footprint "antmicro-footprints:R_0402_1005Metric" (layer "B.Cu")
    (at 158.91 67.47 90)
    (descr "Resistor SMD 0402")
    (tags "resistor SMD 0402")
    (property "Author" "Antmicro")
    (property "License" "Apache-2.0")
    (property "MPN" "CR0402-FX-5101GLF")
    (property "Manufacturer" "Bourns")
    (property "Sheetfile" "power.kicad_sch")
    (property "Sheetname" "Power")
    (property "Tolerance" "1%")
    (property "Val" "5k1")
    (property "ki_description" "SMD Chip Resistor, 5.1 kohm, ± 1%, 63 mW, 0402 [1005 Metric], Thick Film, General Purpose")
    (property "ki_keywords" "0402, SMT, RESISTOR, PASSIVE")
    (attr smd)
    (fp_text reference "R40" (at -0.983 0.491 270) (layer "B.SilkS")
        (effects (font (size 0.7 0.7) (thickness 0.15)) (justify left bottom mirror))
    )
    (fp_text value "R_5k1_0402" (at -1.011843 -1.772047 270) (layer "B.Fab")
        (effects (font (size 0.7 0.7) (thickness 0.15)) (justify left bottom mirror))
    )
    (fp_text user "Author: Antmicro" (at -0.95 -4.169 270) (layer "B.Fab") hide
        (effects (font (size 0.7 0.7) (thickness 0.15)) (justify left bottom mirror))
    )
    (fp_text user "${REFERENCE}" (at -0.95 -3.168 270) (layer "B.Fab") hide
        (effects (font (size 0.7 0.7) (thickness 0.15)) (justify left bottom mirror))
    )
    (fp_text user "License: Apache-2.0" (at -0.95 -5.169 270) (layer "B.Fab") hide
        (effects (font (size 0.7 0.7) (thickness 0.15)) (justify left bottom mirror))
    )
    (fp_rect (start -0.925 0.47) (end 0.925 -0.47)
      (stroke (width 0.05) (type default)) (fill none) (layer "B.CrtYd"))
    (fp_rect (start -0.5 0.25) (end 0.5 -0.25)
      (stroke (width 0.15) (type solid)) (fill none) (layer "B.Fab"))
    (pad "1" smd roundrect (at -0.48 0 90) (size 0.59 0.64) (layers "B.Cu" "B.Paste" "B.Mask") (roundrect_rratio 0.25)
      (net 1 "GND") (pintype "passive"))
    (pad "2" smd roundrect (at 0.48 0 90) (size 0.59 0.64) (layers "B.Cu" "B.Paste" "B.Mask") (roundrect_rratio 0.25)
      (net 11 "CC1") (pintype "passive"))
  )
	(footprint "antmicro-footprints:R_0402_1005Metric" (layer "B.Cu")
    (at 159.91 67.47 90)
    (descr "Resistor SMD 0402")
    (tags "resistor SMD 0402")
    (property "Author" "Antmicro")
    (property "License" "Apache-2.0")
    (property "MPN" "CR0402-FX-5101GLF")
    (property "Manufacturer" "Bourns")
    (property "Sheetfile" "power.kicad_sch")
    (property "Sheetname" "Power")
    (property "Tolerance" "1%")
    (property "Val" "5k1")
    (property "ki_description" "SMD Chip Resistor, 5.1 kohm, ± 1%, 63 mW, 0402 [1005 Metric], Thick Film, General Purpose")
    (property "ki_keywords" "0402, SMT, RESISTOR, PASSIVE")
    (attr smd)
    (fp_text reference "R38" (at -0.983 0.491 270) (layer "B.SilkS")
        (effects (font (size 0.7 0.7) (thickness 0.15)) (justify left bottom mirror))
    )
    (fp_text value "R_5k1_0402" (at -1.011843 -1.772047 270) (layer "B.Fab")
        (effects (font (size 0.7 0.7) (thickness 0.15)) (justify left bottom mirror))
    )
    (fp_text user "License: Apache-2.0" (at -0.95 -5.169 270) (layer "B.Fab") hide
        (effects (font (size 0.7 0.7) (thickness 0.15)) (justify left bottom mirror))
    )
    (fp_text user "${REFERENCE}" (at -0.95 -3.168 270) (layer "B.Fab") hide
        (effects (font (size 0.7 0.7) (thickness 0.15)) (justify left bottom mirror))
    )
    (fp_text user "Author: Antmicro" (at -0.95 -4.169 270) (layer "B.Fab") hide
        (effects (font (size 0.7 0.7) (thickness 0.15)) (justify left bottom mirror))
    )
    (fp_rect (start -0.925 0.47) (end 0.925 -0.47)
      (stroke (width 0.05) (type default)) (fill none) (layer "B.CrtYd"))
    (fp_rect (start -0.5 0.25) (end 0.5 -0.25)
      (stroke (width 0.15) (type solid)) (fill none) (layer "B.Fab"))
    (pad "1" smd roundrect (at -0.48 0 90) (size 0.59 0.64) (layers "B.Cu" "B.Paste" "B.Mask") (roundrect_rratio 0.25)
      (net 1 "GND") (pintype "passive"))
    (pad "2" smd roundrect (at 0.48 0 90) (size 0.59 0.64) (layers "B.Cu" "B.Paste" "B.Mask") (roundrect_rratio 0.25)
      (net 10 "CC2") (pintype "passive"))
  )
	(footprint "antmicro-footprints:C_0402_1005Metric" (layer "B.Cu")
    (at 111.725 82.67 180)
    (descr "Capacitor SMD 0402")
    (tags "capacitor SMD 0402")
    (property "Author" "Antmicro")
    (property "Dielectric" "X5R")
    (property "License" "Apache-2.0")
    (property "MPN" "GRM155R61H104KE14D")
    (property "Manufacturer" "Murata")
    (property "Sheetfile" "power.kicad_sch")
    (property "Sheetname" "Power")
    (property "Val" "100n")
    (property "Voltage" "50V")
    (property "ki_description" "SMD Multilayer Ceramic Capacitor, 0.1 µF, 50 V, 0402 [1005 Metric], ± 10%, X5R, GRM Series")
    (property "ki_keywords" "0402, SMT, CAPACITOR, PASSIVE, CERAMIC, MLCC")
    (attr smd)
    (fp_text reference "C29" (at -1.051 4.692) (layer "B.SilkS")
        (effects (font (size 0.7 0.7) (thickness 0.15)) (justify left bottom mirror))
    )
    (fp_text value "C_100n_0402" (at -1.022927 -2.155213) (layer "B.Fab")
        (effects (font (size 0.7 0.7) (thickness 0.15)) (justify left bottom mirror))
    )
    (fp_text user "License: Apache-2.0" (at -0.939 -5.799) (layer "B.Fab") hide
        (effects (font (size 0.7 0.7) (thickness 0.15)) (justify left bottom mirror))
    )
    (fp_text user "Author: Antmicro" (at -0.939 -3.399) (layer "B.Fab") hide
        (effects (font (size 0.7 0.7) (thickness 0.15)) (justify left bottom mirror))
    )
    (fp_text user "${REFERENCE}" (at -0.939 -4.599) (layer "B.Fab") hide
        (effects (font (size 0.7 0.7) (thickness 0.15)) (justify left bottom mirror))
    )
    (fp_rect (start -0.925 0.47) (end 0.925 -0.47)
      (stroke (width 0.05) (type default)) (fill none) (layer "B.CrtYd"))
    (fp_line (start -0.494 -0.248) (end -0.494 0.25)
      (stroke (width 0.15) (type solid)) (layer "B.Fab"))
    (fp_line (start -0.494 0.25) (end 0.504 0.25)
      (stroke (width 0.15) (type solid)) (layer "B.Fab"))
    (fp_line (start 0.504 -0.248) (end -0.494 -0.248)
      (stroke (width 0.15) (type solid)) (layer "B.Fab"))
    (fp_line (start 0.504 0.25) (end 0.504 -0.248)
      (stroke (width 0.15) (type solid)) (layer "B.Fab"))
    (pad "1" smd roundrect (at -0.48 0 180) (size 0.59 0.64) (layers "B.Cu" "B.Paste" "B.Mask") (roundrect_rratio 0.25)
      (net 97 "Net-(U1-EXTVCC)") (pintype "passive"))
    (pad "2" smd roundrect (at 0.48 0 180) (size 0.59 0.64) (layers "B.Cu" "B.Paste" "B.Mask") (roundrect_rratio 0.25)
      (net 1 "GND") (pintype "passive"))
  )
	(footprint "antmicro-footprints:R_0402_1005Metric" (layer "B.Cu")
    (at 161.41 62.97 180)
    (descr "Resistor SMD 0402")
    (tags "resistor SMD 0402")
    (property "Author" "Antmicro")
    (property "License" "Apache-2.0")
    (property "MPN" "CR0402-FX-1002GLF")
    (property "Manufacturer" "Bourns")
    (property "Sheetfile" "power.kicad_sch")
    (property "Sheetname" "Power")
    (property "Tolerance" "1%")
    (property "Val" "10k")
    (property "ki_description" "SMD Chip Resistor, 10 kohm, ± 1%, 62.5 mW, 0402 [1005 Metric], Thick Film, General Purpose")
    (property "ki_keywords" "0402, SMT, RESISTOR, PASSIVE")
    (attr smd)
    (fp_text reference "R19" (at -3.182 -0.403) (layer "B.SilkS")
        (effects (font (size 0.7 0.7) (thickness 0.15)) (justify left bottom mirror))
    )
    (fp_text value "R_10k_0402" (at -1.011843 -1.772047) (layer "B.Fab")
        (effects (font (size 0.7 0.7) (thickness 0.15)) (justify left bottom mirror))
    )
    (fp_text user "${REFERENCE}" (at -0.95 -3.168) (layer "B.Fab") hide
        (effects (font (size 0.7 0.7) (thickness 0.15)) (justify left bottom mirror))
    )
    (fp_text user "License: Apache-2.0" (at -0.95 -5.169) (layer "B.Fab") hide
        (effects (font (size 0.7 0.7) (thickness 0.15)) (justify left bottom mirror))
    )
    (fp_text user "Author: Antmicro" (at -0.95 -4.169) (layer "B.Fab") hide
        (effects (font (size 0.7 0.7) (thickness 0.15)) (justify left bottom mirror))
    )
    (fp_rect (start -0.925 0.47) (end 0.925 -0.47)
      (stroke (width 0.05) (type default)) (fill none) (layer "B.CrtYd"))
    (fp_rect (start -0.5 0.25) (end 0.5 -0.25)
      (stroke (width 0.15) (type solid)) (fill none) (layer "B.Fab"))
    (pad "1" smd roundrect (at -0.48 0 180) (size 0.59 0.64) (layers "B.Cu" "B.Paste" "B.Mask") (roundrect_rratio 0.25)
      (net 9 "/Power/TPS_3V3") (pintype "passive"))
    (pad "2" smd roundrect (at 0.48 0 180) (size 0.59 0.64) (layers "B.Cu" "B.Paste" "B.Mask") (roundrect_rratio 0.25)
      (net 154 "Net-(U3-GPIO6)") (pintype "passive"))
  )
)
